(kicad_pcb
	(version 20260206)
	(generator "pcbnew")
	(generator_version "10.0")
	(general
		(thickness 1.6)
		(legacy_teardrops no)
	)
	(paper "A4")
	(title_block
		(title "12092022_DA0F0TMDCD0_F0T_Management_Board_D_brd_V3_OCP.brd")
		(comment 1 "Grand Teton / footprints 1279-1284 of 1440")
	)
	(layers
		(0 "F.Cu" signal "TOP")
		(4 "In1.Cu" signal "GND")
		(6 "In2.Cu" signal "IN1")
		(8 "In3.Cu" signal "GND1")
		(10 "In4.Cu" signal "IN2")
		(12 "In5.Cu" signal "VCC")
		(14 "In6.Cu" signal "VCC1")
		(16 "In7.Cu" signal "IN3")
		(18 "In8.Cu" signal "GND2")
		(20 "In9.Cu" signal "IN4")
		(22 "In10.Cu" signal "GND3")
		(2 "B.Cu" signal "BOTTOM")
		(9 "F.Adhes" user "F.Adhesive")
		(11 "B.Adhes" user "B.Adhesive")
		(13 "F.Paste" user "Package Geometry/Pastemask Top")
		(15 "B.Paste" user "Package Geometry/Pastemask Bottom")
		(5 "F.SilkS" user "Ref Des/Silkscreen Top")
		(7 "B.SilkS" user "Ref Des/Silkscreen Bottom")
		(1 "F.Mask" user "Board Geometry/Soldermask Top")
		(3 "B.Mask" user "Board Geometry/Soldermask Bottom")
		(17 "Dwgs.User" user "User.Drawings")
		(19 "Cmts.User" user "User.Comments")
		(21 "Eco1.User" user "User.Eco1")
		(23 "Eco2.User" user "User.Eco2")
		(25 "Edge.Cuts" user "Board Geometry/Outline")
		(27 "Margin" user)
		(31 "F.CrtYd" user "Package Geometry/Place Bound Top")
		(29 "B.CrtYd" user "Package Geometry/Place Bound Bottom")
		(35 "F.Fab" user "Ref Des/Assembly Top")
		(33 "B.Fab" user "Ref Des/Assembly Bottom")
	)
	(footprint ""
		(layer "B.Cu")
		(at 55.14848 -74.242676 -90)
		(property "Reference" "R795"
			(at 0 0 90)
			(layer "B.SilkS")
			(hide yes)
			(effects
				(font
					(size 1.27 1.27)
				)
				(justify mirror)
			)
		)
		(property "Value" ""
			(at 0 0 90)
			(layer "B.Fab")
			(effects
				(font
					(size 1.27 1.27)
				)
				(justify mirror)
			)
		)
		(duplicate_pad_numbers_are_jumpers no)
		(fp_line
			(start -0.7874 0.4064)
			(end 0.7874 0.4064)
			(stroke
				(width 0.1524)
				(type default)
			)
			(layer "B.SilkS")
		)
		(fp_line
			(start 0.7874 0.4064)
			(end 0.7874 -0.4064)
			(stroke
				(width 0.1524)
				(type default)
			)
			(layer "B.SilkS")
		)
		(fp_line
			(start -0.7874 -0.4064)
			(end -0.7874 0.4064)
			(stroke
				(width 0.1524)
				(type default)
			)
			(layer "B.SilkS")
		)
		(fp_line
			(start 0.7874 -0.4064)
			(end -0.7874 -0.4064)
			(stroke
				(width 0.1524)
				(type default)
			)
			(layer "B.SilkS")
		)
		(fp_line
			(start -0.67945 0.3048)
			(end -0.120396 0.3048)
			(stroke
				(width 0.1)
				(type default)
			)
			(layer "B.Fab")
		)
		(fp_line
			(start -0.120396 0.3048)
			(end -0.120396 0.2794)
			(stroke
				(width 0.1)
				(type default)
			)
			(layer "B.Fab")
		)
		(fp_line
			(start 0.12065 0.3048)
			(end 0.67945 0.3048)
			(stroke
				(width 0.1)
				(type default)
			)
			(layer "B.Fab")
		)
		(fp_line
			(start 0.67945 0.3048)
			(end 0.67945 -0.305054)
			(stroke
				(width 0.1)
				(type default)
			)
			(layer "B.Fab")
		)
		(fp_line
			(start -0.120396 0.2794)
			(end 0.12065 0.2794)
			(stroke
				(width 0.1)
				(type default)
			)
			(layer "B.Fab")
		)
		(fp_line
			(start 0.12065 0.2794)
			(end 0.12065 0.3048)
			(stroke
				(width 0.1)
				(type default)
			)
			(layer "B.Fab")
		)
		(fp_line
			(start -0.12065 -0.2794)
			(end -0.12065 -0.3048)
			(stroke
				(width 0.1)
				(type default)
			)
			(layer "B.Fab")
		)
		(fp_line
			(start 0.12065 -0.2794)
			(end -0.12065 -0.2794)
			(stroke
				(width 0.1)
				(type default)
			)
			(layer "B.Fab")
		)
		(fp_line
			(start -0.67945 -0.3048)
			(end -0.67945 0.3048)
			(stroke
				(width 0.1)
				(type default)
			)
			(layer "B.Fab")
		)
		(fp_line
			(start -0.12065 -0.3048)
			(end -0.67945 -0.3048)
			(stroke
				(width 0.1)
				(type default)
			)
			(layer "B.Fab")
		)
		(fp_line
			(start 0.12065 -0.305054)
			(end 0.12065 -0.2794)
			(stroke
				(width 0.1)
				(type default)
			)
			(layer "B.Fab")
		)
		(fp_line
			(start 0.67945 -0.305054)
			(end 0.12065 -0.305054)
			(stroke
				(width 0.1)
				(type default)
			)
			(layer "B.Fab")
		)
		(pad "1" smd circle
			(at 0.40005 0 90)
			(size 0 0)
			(layers "B.Cu" "B.Mask" "B.Paste")
			(net "P1V2_AUX")
		)
		(pad "2" smd circle
			(at -0.40005 0 90)
			(size 0 0)
			(layers "B.Cu" "B.Mask" "B.Paste")
			(net "P1V2_SENSOR")
		)
	)
	(footprint ""
		(layer "B.Cu")
		(at 74.803 -32.131 180)
		(property "Reference" "R669"
			(at 0 0 0)
			(layer "B.SilkS")
			(hide yes)
			(effects
				(font
					(size 1.27 1.27)
				)
				(justify mirror)
			)
		)
		(property "Value" ""
			(at 0 0 0)
			(layer "B.Fab")
			(effects
				(font
					(size 1.27 1.27)
				)
				(justify mirror)
			)
		)
		(duplicate_pad_numbers_are_jumpers no)
		(fp_line
			(start 0.7874 0.4064)
			(end 0.7874 -0.4064)
			(stroke
				(width 0.1524)
				(type default)
			)
			(layer "B.SilkS")
		)
		(fp_line
			(start 0.7874 -0.4064)
			(end -0.7874 -0.4064)
			(stroke
				(width 0.1524)
				(type default)
			)
			(layer "B.SilkS")
		)
		(fp_line
			(start -0.7874 0.4064)
			(end 0.7874 0.4064)
			(stroke
				(width 0.1524)
				(type default)
			)
			(layer "B.SilkS")
		)
		(fp_line
			(start -0.7874 -0.4064)
			(end -0.7874 0.4064)
			(stroke
				(width 0.1524)
				(type default)
			)
			(layer "B.SilkS")
		)
		(fp_line
			(start 0.67945 0.3048)
			(end 0.67945 -0.305054)
			(stroke
				(width 0.1)
				(type default)
			)
			(layer "B.Fab")
		)
		(fp_line
			(start 0.67945 -0.305054)
			(end 0.12065 -0.305054)
			(stroke
				(width 0.1)
				(type default)
			)
			(layer "B.Fab")
		)
		(fp_line
			(start 0.12065 0.3048)
			(end 0.67945 0.3048)
			(stroke
				(width 0.1)
				(type default)
			)
			(layer "B.Fab")
		)
		(fp_line
			(start 0.12065 0.2794)
			(end 0.12065 0.3048)
			(stroke
				(width 0.1)
				(type default)
			)
			(layer "B.Fab")
		)
		(fp_line
			(start 0.12065 -0.2794)
			(end -0.12065 -0.2794)
			(stroke
				(width 0.1)
				(type default)
			)
			(layer "B.Fab")
		)
		(fp_line
			(start 0.12065 -0.305054)
			(end 0.12065 -0.2794)
			(stroke
				(width 0.1)
				(type default)
			)
			(layer "B.Fab")
		)
		(fp_line
			(start -0.120396 0.3048)
			(end -0.120396 0.2794)
			(stroke
				(width 0.1)
				(type default)
			)
			(layer "B.Fab")
		)
		(fp_line
			(start -0.120396 0.2794)
			(end 0.12065 0.2794)
			(stroke
				(width 0.1)
				(type default)
			)
			(layer "B.Fab")
		)
		(fp_line
			(start -0.12065 -0.2794)
			(end -0.12065 -0.3048)
			(stroke
				(width 0.1)
				(type default)
			)
			(layer "B.Fab")
		)
		(fp_line
			(start -0.12065 -0.3048)
			(end -0.67945 -0.3048)
			(stroke
				(width 0.1)
				(type default)
			)
			(layer "B.Fab")
		)
		(fp_line
			(start -0.67945 0.3048)
			(end -0.120396 0.3048)
			(stroke
				(width 0.1)
				(type default)
			)
			(layer "B.Fab")
		)
		(fp_line
			(start -0.67945 -0.3048)
			(end -0.67945 0.3048)
			(stroke
				(width 0.1)
				(type default)
			)
			(layer "B.Fab")
		)
		(pad "1" smd circle
			(at 0.40005 0)
			(size 0 0)
			(layers "B.Cu" "B.Mask" "B.Paste")
			(net "LED_POSTCODE_7")
		)
		(pad "2" smd circle
			(at -0.40005 0)
			(size 0 0)
			(layers "B.Cu" "B.Mask" "B.Paste")
			(net "LED_POSTCODE_7_R1")
		)
	)
	(footprint ""
		(layer "B.Cu")
		(at 31.9532 -60.5282)
		(property "Reference" "C290"
			(at 0 0 0)
			(layer "B.SilkS")
			(hide yes)
			(effects
				(font
					(size 1.27 1.27)
				)
				(justify mirror)
			)
		)
		(property "Value" ""
			(at 0 0 0)
			(layer "B.Fab")
			(effects
				(font
					(size 1.27 1.27)
				)
				(justify mirror)
			)
		)
		(duplicate_pad_numbers_are_jumpers no)
		(fp_line
			(start -0.7874 -0.4064)
			(end -0.7874 0.4064)
			(stroke
				(width 0.1524)
				(type default)
			)
			(layer "B.SilkS")
		)
		(fp_line
			(start -0.7874 0.4064)
			(end 0.7874 0.4064)
			(stroke
				(width 0.1524)
				(type default)
			)
			(layer "B.SilkS")
		)
		(fp_line
			(start 0.7874 -0.4064)
			(end -0.7874 -0.4064)
			(stroke
				(width 0.1524)
				(type default)
			)
			(layer "B.SilkS")
		)
		(fp_line
			(start 0.7874 0.4064)
			(end 0.7874 -0.4064)
			(stroke
				(width 0.1524)
				(type default)
			)
			(layer "B.SilkS")
		)
		(fp_line
			(start -0.67945 -0.3048)
			(end -0.67945 0.3048)
			(stroke
				(width 0.1)
				(type default)
			)
			(layer "B.Fab")
		)
		(fp_line
			(start -0.67945 0.3048)
			(end -0.120396 0.3048)
			(stroke
				(width 0.1)
				(type default)
			)
			(layer "B.Fab")
		)
		(fp_line
			(start -0.12065 -0.3048)
			(end -0.67945 -0.3048)
			(stroke
				(width 0.1)
				(type default)
			)
			(layer "B.Fab")
		)
		(fp_line
			(start -0.12065 -0.2794)
			(end -0.12065 -0.3048)
			(stroke
				(width 0.1)
				(type default)
			)
			(layer "B.Fab")
		)
		(fp_line
			(start -0.120396 0.2794)
			(end 0.12065 0.2794)
			(stroke
				(width 0.1)
				(type default)
			)
			(layer "B.Fab")
		)
		(fp_line
			(start -0.120396 0.3048)
			(end -0.120396 0.2794)
			(stroke
				(width 0.1)
				(type default)
			)
			(layer "B.Fab")
		)
		(fp_line
			(start 0.12065 -0.305054)
			(end 0.12065 -0.2794)
			(stroke
				(width 0.1)
				(type default)
			)
			(layer "B.Fab")
		)
		(fp_line
			(start 0.12065 -0.2794)
			(end -0.12065 -0.2794)
			(stroke
				(width 0.1)
				(type default)
			)
			(layer "B.Fab")
		)
		(fp_line
			(start 0.12065 0.2794)
			(end 0.12065 0.3048)
			(stroke
				(width 0.1)
				(type default)
			)
			(layer "B.Fab")
		)
		(fp_line
			(start 0.12065 0.3048)
			(end 0.67945 0.3048)
			(stroke
				(width 0.1)
				(type default)
			)
			(layer "B.Fab")
		)
		(fp_line
			(start 0.67945 -0.305054)
			(end 0.12065 -0.305054)
			(stroke
				(width 0.1)
				(type default)
			)
			(layer "B.Fab")
		)
		(fp_line
			(start 0.67945 0.3048)
			(end 0.67945 -0.305054)
			(stroke
				(width 0.1)
				(type default)
			)
			(layer "B.Fab")
		)
		(pad "1" smd circle
			(at 0.40005 0 180)
			(size 0 0)
			(layers "B.Cu" "B.Mask" "B.Paste")
			(net "P12V_SENSOR")
		)
		(pad "2" smd circle
			(at -0.40005 0 180)
			(size 0 0)
			(layers "B.Cu" "B.Mask" "B.Paste")
			(net "GND")
		)
	)
	(footprint ""
		(layer "B.Cu")
		(at 14.478 -21.844 180)
		(property "Reference" "R812"
			(at 0 0 0)
			(layer "B.SilkS")
			(hide yes)
			(effects
				(font
					(size 1.27 1.27)
				)
				(justify mirror)
			)
		)
		(property "Value" ""
			(at 0 0 0)
			(layer "B.Fab")
			(effects
				(font
					(size 1.27 1.27)
				)
				(justify mirror)
			)
		)
		(duplicate_pad_numbers_are_jumpers no)
		(fp_line
			(start 0.7874 0.4064)
			(end 0.7874 -0.4064)
			(stroke
				(width 0.1524)
				(type default)
			)
			(layer "B.SilkS")
		)
		(fp_line
			(start 0.7874 -0.4064)
			(end -0.7874 -0.4064)
			(stroke
				(width 0.1524)
				(type default)
			)
			(layer "B.SilkS")
		)
		(fp_line
			(start -0.7874 0.4064)
			(end 0.7874 0.4064)
			(stroke
				(width 0.1524)
				(type default)
			)
			(layer "B.SilkS")
		)
		(fp_line
			(start -0.7874 -0.4064)
			(end -0.7874 0.4064)
			(stroke
				(width 0.1524)
				(type default)
			)
			(layer "B.SilkS")
		)
		(fp_line
			(start 0.67945 0.3048)
			(end 0.67945 -0.305054)
			(stroke
				(width 0.1)
				(type default)
			)
			(layer "B.Fab")
		)
		(fp_line
			(start 0.67945 -0.305054)
			(end 0.12065 -0.305054)
			(stroke
				(width 0.1)
				(type default)
			)
			(layer "B.Fab")
		)
		(fp_line
			(start 0.12065 0.3048)
			(end 0.67945 0.3048)
			(stroke
				(width 0.1)
				(type default)
			)
			(layer "B.Fab")
		)
		(fp_line
			(start 0.12065 0.2794)
			(end 0.12065 0.3048)
			(stroke
				(width 0.1)
				(type default)
			)
			(layer "B.Fab")
		)
		(fp_line
			(start 0.12065 -0.2794)
			(end -0.12065 -0.2794)
			(stroke
				(width 0.1)
				(type default)
			)
			(layer "B.Fab")
		)
		(fp_line
			(start 0.12065 -0.305054)
			(end 0.12065 -0.2794)
			(stroke
				(width 0.1)
				(type default)
			)
			(layer "B.Fab")
		)
		(fp_line
			(start -0.120396 0.3048)
			(end -0.120396 0.2794)
			(stroke
				(width 0.1)
				(type default)
			)
			(layer "B.Fab")
		)
		(fp_line
			(start -0.120396 0.2794)
			(end 0.12065 0.2794)
			(stroke
				(width 0.1)
				(type default)
			)
			(layer "B.Fab")
		)
		(fp_line
			(start -0.12065 -0.2794)
			(end -0.12065 -0.3048)
			(stroke
				(width 0.1)
				(type default)
			)
			(layer "B.Fab")
		)
		(fp_line
			(start -0.12065 -0.3048)
			(end -0.67945 -0.3048)
			(stroke
				(width 0.1)
				(type default)
			)
			(layer "B.Fab")
		)
		(fp_line
			(start -0.67945 0.3048)
			(end -0.120396 0.3048)
			(stroke
				(width 0.1)
				(type default)
			)
			(layer "B.Fab")
		)
		(fp_line
			(start -0.67945 -0.3048)
			(end -0.67945 0.3048)
			(stroke
				(width 0.1)
				(type default)
			)
			(layer "B.Fab")
		)
		(pad "1" smd circle
			(at 0.40005 0)
			(size 0 0)
			(layers "B.Cu" "B.Mask" "B.Paste")
			(net "PWR_LED_BUF_N")
		)
		(pad "2" smd circle
			(at -0.40005 0)
			(size 0 0)
			(layers "B.Cu" "B.Mask" "B.Paste")
			(net "PWR_LED_BUF_N_R")
		)
	)
	(footprint ""
		(layer "B.Cu")
		(at 80.755744 -35.540188 -90)
		(property "Reference" "R326"
			(at 0 0 90)
			(layer "B.SilkS")
			(hide yes)
			(effects
				(font
					(size 1.27 1.27)
				)
				(justify mirror)
			)
		)
		(property "Value" ""
			(at 0 0 90)
			(layer "B.Fab")
			(effects
				(font
					(size 1.27 1.27)
				)
				(justify mirror)
			)
		)
		(duplicate_pad_numbers_are_jumpers no)
		(fp_line
			(start -0.7874 0.4064)
			(end 0.7874 0.4064)
			(stroke
				(width 0.1524)
				(type default)
			)
			(layer "B.SilkS")
		)
		(fp_line
			(start 0.7874 0.4064)
			(end 0.7874 -0.4064)
			(stroke
				(width 0.1524)
				(type default)
			)
			(layer "B.SilkS")
		)
		(fp_line
			(start -0.7874 -0.4064)
			(end -0.7874 0.4064)
			(stroke
				(width 0.1524)
				(type default)
			)
			(layer "B.SilkS")
		)
		(fp_line
			(start 0.7874 -0.4064)
			(end -0.7874 -0.4064)
			(stroke
				(width 0.1524)
				(type default)
			)
			(layer "B.SilkS")
		)
		(fp_line
			(start -0.67945 0.3048)
			(end -0.120396 0.3048)
			(stroke
				(width 0.1)
				(type default)
			)
			(layer "B.Fab")
		)
		(fp_line
			(start -0.120396 0.3048)
			(end -0.120396 0.2794)
			(stroke
				(width 0.1)
				(type default)
			)
			(layer "B.Fab")
		)
		(fp_line
			(start 0.12065 0.3048)
			(end 0.67945 0.3048)
			(stroke
				(width 0.1)
				(type default)
			)
			(layer "B.Fab")
		)
		(fp_line
			(start 0.67945 0.3048)
			(end 0.67945 -0.305054)
			(stroke
				(width 0.1)
				(type default)
			)
			(layer "B.Fab")
		)
		(fp_line
			(start -0.120396 0.2794)
			(end 0.12065 0.2794)
			(stroke
				(width 0.1)
				(type default)
			)
			(layer "B.Fab")
		)
		(fp_line
			(start 0.12065 0.2794)
			(end 0.12065 0.3048)
			(stroke
				(width 0.1)
				(type default)
			)
			(layer "B.Fab")
		)
		(fp_line
			(start -0.12065 -0.2794)
			(end -0.12065 -0.3048)
			(stroke
				(width 0.1)
				(type default)
			)
			(layer "B.Fab")
		)
		(fp_line
			(start 0.12065 -0.2794)
			(end -0.12065 -0.2794)
			(stroke
				(width 0.1)
				(type default)
			)
			(layer "B.Fab")
		)
		(fp_line
			(start -0.67945 -0.3048)
			(end -0.67945 0.3048)
			(stroke
				(width 0.1)
				(type default)
			)
			(layer "B.Fab")
		)
		(fp_line
			(start -0.12065 -0.3048)
			(end -0.67945 -0.3048)
			(stroke
				(width 0.1)
				(type default)
			)
			(layer "B.Fab")
		)
		(fp_line
			(start 0.12065 -0.305054)
			(end 0.12065 -0.2794)
			(stroke
				(width 0.1)
				(type default)
			)
			(layer "B.Fab")
		)
		(fp_line
			(start 0.67945 -0.305054)
			(end 0.12065 -0.305054)
			(stroke
				(width 0.1)
				(type default)
			)
			(layer "B.Fab")
		)
		(pad "1" smd circle
			(at 0.40005 0 90)
			(size 0 0)
			(layers "B.Cu" "B.Mask" "B.Paste")
			(net "GND")
		)
		(pad "2" smd circle
			(at -0.40005 0 90)
			(size 0 0)
			(layers "B.Cu" "B.Mask" "B.Paste")
			(net "M_BMC_DDR4_MA<0>")
		)
	)
	(footprint ""
		(layer "B.Cu")
		(at 50.292 -66.7131 -90)
		(property "Reference" "R796"
			(at 0 0 90)
			(layer "B.SilkS")
			(hide yes)
			(effects
				(font
					(size 1.27 1.27)
				)
				(justify mirror)
			)
		)
		(property "Value" ""
			(at 0 0 90)
			(layer "B.Fab")
			(effects
				(font
					(size 1.27 1.27)
				)
				(justify mirror)
			)
		)
		(duplicate_pad_numbers_are_jumpers no)
		(fp_line
			(start -0.7874 0.4064)
			(end 0.7874 0.4064)
			(stroke
				(width 0.1524)
				(type default)
			)
			(layer "B.SilkS")
		)
		(fp_line
			(start 0.7874 0.4064)
			(end 0.7874 -0.4064)
			(stroke
				(width 0.1524)
				(type default)
			)
			(layer "B.SilkS")
		)
		(fp_line
			(start -0.7874 -0.4064)
			(end -0.7874 0.4064)
			(stroke
				(width 0.1524)
				(type default)
			)
			(layer "B.SilkS")
		)
		(fp_line
			(start 0.7874 -0.4064)
			(end -0.7874 -0.4064)
			(stroke
				(width 0.1524)
				(type default)
			)
			(layer "B.SilkS")
		)
		(fp_line
			(start -0.67945 0.3048)
			(end -0.120396 0.3048)
			(stroke
				(width 0.1)
				(type default)
			)
			(layer "B.Fab")
		)
		(fp_line
			(start -0.120396 0.3048)
			(end -0.120396 0.2794)
			(stroke
				(width 0.1)
				(type default)
			)
			(layer "B.Fab")
		)
		(fp_line
			(start 0.12065 0.3048)
			(end 0.67945 0.3048)
			(stroke
				(width 0.1)
				(type default)
			)
			(layer "B.Fab")
		)
		(fp_line
			(start 0.67945 0.3048)
			(end 0.67945 -0.305054)
			(stroke
				(width 0.1)
				(type default)
			)
			(layer "B.Fab")
		)
		(fp_line
			(start -0.120396 0.2794)
			(end 0.12065 0.2794)
			(stroke
				(width 0.1)
				(type default)
			)
			(layer "B.Fab")
		)
		(fp_line
			(start 0.12065 0.2794)
			(end 0.12065 0.3048)
			(stroke
				(width 0.1)
				(type default)
			)
			(layer "B.Fab")
		)
		(fp_line
			(start -0.12065 -0.2794)
			(end -0.12065 -0.3048)
			(stroke
				(width 0.1)
				(type default)
			)
			(layer "B.Fab")
		)
		(fp_line
			(start 0.12065 -0.2794)
			(end -0.12065 -0.2794)
			(stroke
				(width 0.1)
				(type default)
			)
			(layer "B.Fab")
		)
		(fp_line
			(start -0.67945 -0.3048)
			(end -0.67945 0.3048)
			(stroke
				(width 0.1)
				(type default)
			)
			(layer "B.Fab")
		)
		(fp_line
			(start -0.12065 -0.3048)
			(end -0.67945 -0.3048)
			(stroke
				(width 0.1)
				(type default)
			)
			(layer "B.Fab")
		)
		(fp_line
			(start 0.12065 -0.305054)
			(end 0.12065 -0.2794)
			(stroke
				(width 0.1)
				(type default)
			)
			(layer "B.Fab")
		)
		(fp_line
			(start 0.67945 -0.305054)
			(end 0.12065 -0.305054)
			(stroke
				(width 0.1)
				(type default)
			)
			(layer "B.Fab")
		)
		(pad "1" smd circle
			(at 0.40005 0 90)
			(size 0 0)
			(layers "B.Cu" "B.Mask" "B.Paste")
			(net "P1V0_AUX")
		)
		(pad "2" smd circle
			(at -0.40005 0 90)
			(size 0 0)
			(layers "B.Cu" "B.Mask" "B.Paste")
			(net "P1V0_SENSOR")
		)
	)
)
